# T6G (Grand Teton) — schematic netlist excerpt (pin names and nets, part order shuffled) for the footprints in the layout excerpt that follows; sources: Cadence DE-HDL packaged netlist, KiCad conversion of 04192023_DAF0TMB3IC0_F0TG_MB_C_brd_V02_OCP.brd

R4557  Q_RES  33.2 1% CHIP  pkg 0402LF  page 81 : A = HPDB_HSC_PWRGD_ISO ; B = HPDB_HSC_PWRGD_ISO_R
PC88_2  Q_CAP  1UF 25V 10% X6S  pkg C0402  page 201 : A = SW_P12V_AUX_PVDDCR_CPU1_P0_FLT ; B = GND

(kicad_pcb
	(version 20260206)
	(generator "pcbnew")
	(generator_version "10.0")
	(general
		(thickness 1.6)
		(legacy_teardrops no)
	)
	(paper "A4")
	(title_block
		(title "04192023_DAF0TMB3IC0_F0TG_MB_C_brd_V02_OCP.brd")
		(comment 1 "Grand Teton / footprints 4779-4780 of 8354")
	)
	(layers
		(0 "F.Cu" signal "TOP")
		(4 "In1.Cu" signal "GND")
		(6 "In2.Cu" signal "IN1")
		(8 "In3.Cu" signal "GND1")
		(10 "In4.Cu" signal "IN2")
		(12 "In5.Cu" signal "GND2")
		(14 "In6.Cu" signal "IN3")
		(16 "In7.Cu" signal "GND3")
		(18 "In8.Cu" signal "VCC")
		(20 "In9.Cu" signal "VCC1")
		(22 "In10.Cu" signal "GND4")
		(24 "In11.Cu" signal "IN4")
		(26 "In12.Cu" signal "GND5")
		(28 "In13.Cu" signal "IN5")
		(30 "In14.Cu" signal "GND6")
		(32 "In15.Cu" signal "IN6")
		(34 "In16.Cu" signal "GND7")
		(2 "B.Cu" signal "BOTTOM")
		(9 "F.Adhes" user "F.Adhesive")
		(11 "B.Adhes" user "B.Adhesive")
		(13 "F.Paste" user "Package Geometry/Pastemask Top")
		(15 "B.Paste" user "Package Geometry/Pastemask Bottom")
		(5 "F.SilkS" user "Ref Des/Silkscreen Top")
		(7 "B.SilkS" user "Ref Des/Silkscreen Bottom")
		(1 "F.Mask" user "Board Geometry/Soldermask Top")
		(3 "B.Mask" user "Board Geometry/Soldermask Bottom")
		(17 "Dwgs.User" user "User.Drawings")
		(19 "Cmts.User" user "User.Comments")
		(21 "Eco1.User" user "User.Eco1")
		(23 "Eco2.User" user "User.Eco2")
		(25 "Edge.Cuts" user "Board Geometry/Outline")
		(27 "Margin" user)
		(31 "F.CrtYd" user "Package Geometry/Place Bound Top")
		(29 "B.CrtYd" user "Package Geometry/Place Bound Bottom")
		(35 "F.Fab" user "Ref Des/Assembly Top")
		(33 "B.Fab" user "Ref Des/Assembly Bottom")
	)
	(footprint ""
		(layer "F.Cu")
		(at 205.214982 -116.673376 180)
		(property "Reference" "R4557"
			(at 0 0 180)
			(layer "F.SilkS")
			(hide yes)
			(effects
				(font
					(size 1.27 1.27)
				)
			)
		)
		(property "Value" ""
			(at 0 0 180)
			(layer "F.Fab")
			(effects
				(font
					(size 1.27 1.27)
				)
			)
		)
		(duplicate_pad_numbers_are_jumpers no)
		(fp_line
			(start 0.7874 0.4064)
			(end -0.7874 0.4064)
			(stroke
				(width 0.1524)
				(type default)
			)
			(layer "F.SilkS")
		)
		(fp_line
			(start 0.7874 -0.4064)
			(end 0.7874 0.4064)
			(stroke
				(width 0.1524)
				(type default)
			)
			(layer "F.SilkS")
		)
		(fp_line
			(start -0.7874 0.4064)
			(end -0.7874 -0.4064)
			(stroke
				(width 0.1524)
				(type default)
			)
			(layer "F.SilkS")
		)
		(fp_line
			(start -0.7874 -0.4064)
			(end 0.7874 -0.4064)
			(stroke
				(width 0.1524)
				(type default)
			)
			(layer "F.SilkS")
		)
		(fp_line
			(start 0.67945 0.3048)
			(end 0.120396 0.3048)
			(stroke
				(width 0.1)
				(type default)
			)
			(layer "F.Fab")
		)
		(fp_line
			(start 0.67945 -0.3048)
			(end 0.67945 0.3048)
			(stroke
				(width 0.1)
				(type default)
			)
			(layer "F.Fab")
		)
		(fp_line
			(start 0.12065 -0.2794)
			(end 0.12065 -0.3048)
			(stroke
				(width 0.1)
				(type default)
			)
			(layer "F.Fab")
		)
		(fp_line
			(start 0.12065 -0.3048)
			(end 0.67945 -0.3048)
			(stroke
				(width 0.1)
				(type default)
			)
			(layer "F.Fab")
		)
		(fp_line
			(start 0.120396 0.3048)
			(end 0.120396 0.2794)
			(stroke
				(width 0.1)
				(type default)
			)
			(layer "F.Fab")
		)
		(fp_line
			(start 0.120396 0.2794)
			(end -0.12065 0.2794)
			(stroke
				(width 0.1)
				(type default)
			)
			(layer "F.Fab")
		)
		(fp_line
			(start -0.12065 0.3048)
			(end -0.67945 0.3048)
			(stroke
				(width 0.1)
				(type default)
			)
			(layer "F.Fab")
		)
		(fp_line
			(start -0.12065 0.2794)
			(end -0.12065 0.3048)
			(stroke
				(width 0.1)
				(type default)
			)
			(layer "F.Fab")
		)
		(fp_line
			(start -0.12065 -0.2794)
			(end 0.12065 -0.2794)
			(stroke
				(width 0.1)
				(type default)
			)
			(layer "F.Fab")
		)
		(fp_line
			(start -0.12065 -0.305054)
			(end -0.12065 -0.2794)
			(stroke
				(width 0.1)
				(type default)
			)
			(layer "F.Fab")
		)
		(fp_line
			(start -0.67945 0.3048)
			(end -0.67945 -0.305054)
			(stroke
				(width 0.1)
				(type default)
			)
			(layer "F.Fab")
		)
		(fp_line
			(start -0.67945 -0.305054)
			(end -0.12065 -0.305054)
			(stroke
				(width 0.1)
				(type default)
			)
			(layer "F.Fab")
		)
		(pad "1" smd circle
			(at -0.40005 0 180)
			(size 0 0)
			(layers "F.Cu" "F.Mask" "F.Paste")
			(net "HPDB_HSC_PWRGD_ISO")
		)
		(pad "2" smd circle
			(at 0.40005 0 180)
			(size 0 0)
			(layers "F.Cu" "F.Mask" "F.Paste")
			(net "HPDB_HSC_PWRGD_ISO_R")
		)
	)
	(footprint ""
		(layer "F.Cu")
		(at 330.374244 -335.129632 -90)
		(property "Reference" "PC88_2"
			(at 0 0 270)
			(layer "F.SilkS")
			(hide yes)
			(effects
				(font
					(size 1.27 1.27)
				)
			)
		)
		(property "Value" ""
			(at 0 0 270)
			(layer "F.Fab")
			(effects
				(font
					(size 1.27 1.27)
				)
			)
		)
		(duplicate_pad_numbers_are_jumpers no)
		(fp_line
			(start -0.7874 0.4064)
			(end -0.7874 -0.4064)
			(stroke
				(width 0.1524)
				(type default)
			)
			(layer "F.SilkS")
		)
		(fp_line
			(start 0.7874 0.4064)
			(end -0.7874 0.4064)
			(stroke
				(width 0.1524)
				(type default)
			)
			(layer "F.SilkS")
		)
		(fp_line
			(start -0.7874 -0.4064)
			(end 0.7874 -0.4064)
			(stroke
				(width 0.1524)
				(type default)
			)
			(layer "F.SilkS")
		)
		(fp_line
			(start 0.7874 -0.4064)
			(end 0.7874 0.4064)
			(stroke
				(width 0.1524)
				(type default)
			)
			(layer "F.SilkS")
		)
		(fp_line
			(start -0.67945 0.3048)
			(end -0.67945 -0.305054)
			(stroke
				(width 0.1)
				(type default)
			)
			(layer "F.Fab")
		)
		(fp_line
			(start -0.12065 0.3048)
			(end -0.67945 0.3048)
			(stroke
				(width 0.1)
				(type default)
			)
			(layer "F.Fab")
		)
		(fp_line
			(start 0.120396 0.3048)
			(end 0.120396 0.2794)
			(stroke
				(width 0.1)
				(type default)
			)
			(layer "F.Fab")
		)
		(fp_line
			(start 0.67945 0.3048)
			(end 0.120396 0.3048)
			(stroke
				(width 0.1)
				(type default)
			)
			(layer "F.Fab")
		)
		(fp_line
			(start -0.12065 0.2794)
			(end -0.12065 0.3048)
			(stroke
				(width 0.1)
				(type default)
			)
			(layer "F.Fab")
		)
		(fp_line
			(start 0.120396 0.2794)
			(end -0.12065 0.2794)
			(stroke
				(width 0.1)
				(type default)
			)
			(layer "F.Fab")
		)
		(fp_line
			(start -0.12065 -0.2794)
			(end 0.12065 -0.2794)
			(stroke
				(width 0.1)
				(type default)
			)
			(layer "F.Fab")
		)
		(fp_line
			(start 0.12065 -0.2794)
			(end 0.12065 -0.3048)
			(stroke
				(width 0.1)
				(type default)
			)
			(layer "F.Fab")
		)
		(fp_line
			(start 0.12065 -0.3048)
			(end 0.67945 -0.3048)
			(stroke
				(width 0.1)
				(type default)
			)
			(layer "F.Fab")
		)
		(fp_line
			(start 0.67945 -0.3048)
			(end 0.67945 0.3048)
			(stroke
				(width 0.1)
				(type default)
			)
			(layer "F.Fab")
		)
		(fp_line
			(start -0.67945 -0.305054)
			(end -0.12065 -0.305054)
			(stroke
				(width 0.1)
				(type default)
			)
			(layer "F.Fab")
		)
		(fp_line
			(start -0.12065 -0.305054)
			(end -0.12065 -0.2794)
			(stroke
				(width 0.1)
				(type default)
			)
			(layer "F.Fab")
		)
		(pad "1" smd circle
			(at -0.40005 0 270)
			(size 0 0)
			(layers "F.Cu" "F.Mask" "F.Paste")
			(net "SW_P12V_AUX_PVDDCR_CPU1_P0_FLT")
		)
		(pad "2" smd circle
			(at 0.40005 0 270)
			(size 0 0)
			(layers "F.Cu" "F.Mask" "F.Paste")
			(net "GND")
		)
	)
)
